FILE_TYPE = MACRO_DRAWING;
SET COLOR_WIRE YELLOW;
SET COLOR_PROP ORANGE;
SET COLOR_DOT WHITE;
SET COLOR_ARC YELLOW;
SET COLOR_BODY GREEN;
SET COLOR_NOTE PURPLE;
SET PROP_DISPLAY VALUE;
SET PAGE_NUMBER P132;
FORCEADD OFFPAGE..1
(-6600 4050);
FORCEPROP 2 LAST $XR0 122 
J 0
(-6852 4050);
DISPLAY 0.638298 (-6852 4050);
PAINT MONO (-6852 4050);
FORCEPROP 2 LAST CDS_LIB mstr_standard
J 0
(-6600 4050);
DISPLAY 0.808511 (-6600 4050);
DISPLAY INVISIBLE (-6600 4050);
FORCEPROP 2 LAST BOM_COST SB
J 0
(-6275 4100);
DISPLAY 1.361702 (-6275 4100);
PAINT WHITE (-6275 4100);
DISPLAY INVISIBLE (-6275 4100);
FORCEPROP 1 LAST OFFPAGE TRUE
J 0
(-6275 3925);
DISPLAY 0.872340 (-6275 3925);
PAINT GREEN (-6275 3925);
DISPLAY INVISIBLE (-6275 3925);
FORCEPROP 1 LAST COMMENT_BODY TRUE
J 0
(-6475 3950);
DISPLAY 0.872340 (-6475 3950);
PAINT GREEN (-6475 3950);
DISPLAY INVISIBLE (-6475 3950);
FORCEPROP 2 LAST PATH I10
J 0
(-6850 4100);
DISPLAY 1.021277 (-6850 4100);
DISPLAY INVISIBLE (-6850 4100);
FORCEPROP 2 LAST ROOM SB_PU_PD
J 0
(-6275 4100);
DISPLAY 1.361702 (-6275 4100);
PAINT RED (-6275 4100);
DISPLAY INVISIBLE (-6275 4100);
FORCEADD OFFPAGE..1
(-6600 3575);
FORCEPROP 2 LAST $XR0 128 
J 0
(-6852 3575);
DISPLAY 0.638298 (-6852 3575);
PAINT MONO (-6852 3575);
FORCEPROP 2 LAST BOM_COST SB
J 0
(-6275 3625);
DISPLAY 1.361702 (-6275 3625);
PAINT WHITE (-6275 3625);
DISPLAY INVISIBLE (-6275 3625);
FORCEPROP 2 LAST CDS_LIB mstr_standard
J 0
(-6600 3575);
DISPLAY INVISIBLE (-6600 3575);
FORCEPROP 1 LAST OFFPAGE TRUE
J 0
(-6275 3450);
DISPLAY 0.872340 (-6275 3450);
PAINT GREEN (-6275 3450);
DISPLAY INVISIBLE (-6275 3450);
FORCEPROP 1 LAST COMMENT_BODY TRUE
J 0
(-6475 3475);
DISPLAY 0.872340 (-6475 3475);
PAINT GREEN (-6475 3475);
DISPLAY INVISIBLE (-6475 3475);
FORCEPROP 2 LAST PATH I11
J 0
(-6550 3650);
DISPLAY 1.021277 (-6550 3650);
DISPLAY INVISIBLE (-6550 3650);
FORCEPROP 2 LAST ROOM SB_PU_PD
J 0
(-6275 3625);
DISPLAY 1.361702 (-6275 3625);
PAINT RED (-6275 3625);
DISPLAY INVISIBLE (-6275 3625);
FORCEADD Q_RES..1
(-5225 3400);
FORCEPROP 1 LAST LOCATION R1006
J 0
(-5475 3400);
DISPLAY 0.489362 (-5475 3400);
PAINT SKYBLUE (-5475 3400);
FORCEPROP 0 LAST $SEC 1
J 0
(-5275 3500);
DISPLAY 0.680851 (-5275 3500);
PAINT MONO (-5275 3500);
DISPLAY INVISIBLE (-5275 3500);
FORCEPROP 0 LAST CDS_SEC 1
J 0
(-5275 3500);
DISPLAY 1.021277 (-5275 3500);
DISPLAY INVISIBLE (-5275 3500);
FORCEPROP 1 LASTPIN (-5325 3400) $PN 1
J 0
(-5313 3412);
DISPLAY 0.489362 (-5313 3412);
PAINT MONO (-5313 3412);
FORCEPROP 1 LASTPIN (-5125 3400) $PN 2
J 0
(-5163 3412);
DISPLAY 0.489362 (-5163 3412);
PAINT MONO (-5163 3412);
FORCEPROP 1 LAST TOLERANCE 5%
J 0
(-5000 3400);
DISPLAY 0.489362 (-5000 3400);
PAINT SKYBLUE (-5000 3400);
FORCEPROP 1 LAST VALUE 33
J 2
(-5025 3400);
DISPLAY 0.489362 (-5025 3400);
PAINT SKYBLUE (-5025 3400);
FORCEPROP 2 LAST CDS_LIB pure_quanta
J 0
(-5225 3400);
DISPLAY INVISIBLE (-5225 3400);
FORCEPROP 1 LAST PATH I12
J 0
(-5275 3550);
DISPLAY 0.978723 (-5275 3550);
PAINT WHITE (-5275 3550);
DISPLAY INVISIBLE (-5275 3550);
FORCEPROP 1 LAST WATTAGE 1/16W
J 2
(-5050 3525);
DISPLAY 0.617021 (-5050 3525);
PAINT SKYBLUE (-5050 3525);
DISPLAY INVISIBLE (-5050 3525);
FORCEPROP 1 LAST MATERIAL CHIP
J 0
(-5325 3525);
DISPLAY 0.617021 (-5325 3525);
PAINT SKYBLUE (-5325 3525);
DISPLAY INVISIBLE (-5325 3525);
FORCEPROP 1 LAST PART_NUMBER CS03302JB29
J 0
(-5325 3475);
DISPLAY 0.617021 (-5325 3475);
PAINT SKYBLUE (-5325 3475);
DISPLAY INVISIBLE (-5325 3475);
FORCEPROP 1 LAST PACK_TYPE 0402LF
J 0
(-4925 3400);
DISPLAY 0.617021 (-4925 3400);
PAINT SKYBLUE (-4925 3400);
DISPLAY INVISIBLE (-4925 3400);
FORCEADD Q_RES..1
(-5250 2525);
FORCEPROP 1 LAST LOCATION R1002
J 0
(-5500 2525);
DISPLAY 0.489362 (-5500 2525);
PAINT SKYBLUE (-5500 2525);
FORCEPROP 0 LAST $SEC 1
J 0
(-5300 2625);
DISPLAY 0.680851 (-5300 2625);
PAINT MONO (-5300 2625);
DISPLAY INVISIBLE (-5300 2625);
FORCEPROP 0 LAST CDS_SEC 1
J 0
(-5300 2625);
DISPLAY 1.021277 (-5300 2625);
DISPLAY INVISIBLE (-5300 2625);
FORCEPROP 1 LASTPIN (-5350 2525) $PN 1
J 0
(-5338 2537);
DISPLAY 0.489362 (-5338 2537);
PAINT MONO (-5338 2537);
FORCEPROP 1 LASTPIN (-5150 2525) $PN 2
J 0
(-5188 2537);
DISPLAY 0.489362 (-5188 2537);
PAINT MONO (-5188 2537);
FORCEPROP 1 LAST TOLERANCE 5%
J 0
(-5025 2525);
DISPLAY 0.489362 (-5025 2525);
PAINT SKYBLUE (-5025 2525);
FORCEPROP 1 LAST VALUE 33
J 2
(-5050 2525);
DISPLAY 0.489362 (-5050 2525);
PAINT SKYBLUE (-5050 2525);
FORCEPROP 2 LAST CDS_LIB pure_quanta
J 0
(-5250 2525);
DISPLAY INVISIBLE (-5250 2525);
FORCEPROP 1 LAST PATH I15
J 0
(-5300 2675);
DISPLAY 0.978723 (-5300 2675);
PAINT WHITE (-5300 2675);
DISPLAY INVISIBLE (-5300 2675);
FORCEPROP 1 LAST WATTAGE 1/16W
J 2
(-5075 2650);
DISPLAY 0.617021 (-5075 2650);
PAINT SKYBLUE (-5075 2650);
DISPLAY INVISIBLE (-5075 2650);
FORCEPROP 1 LAST MATERIAL CHIP
J 0
(-5350 2650);
DISPLAY 0.617021 (-5350 2650);
PAINT SKYBLUE (-5350 2650);
DISPLAY INVISIBLE (-5350 2650);
FORCEPROP 1 LAST PART_NUMBER CS03302JB29
J 0
(-5350 2600);
DISPLAY 0.617021 (-5350 2600);
PAINT SKYBLUE (-5350 2600);
DISPLAY INVISIBLE (-5350 2600);
FORCEPROP 1 LAST PACK_TYPE 0402LF
J 0
(-4950 2525);
DISPLAY 0.617021 (-4950 2525);
PAINT SKYBLUE (-4950 2525);
DISPLAY INVISIBLE (-4950 2525);
FORCEADD Q_RES..1
(-5250 2075);
FORCEPROP 1 LAST LOCATION R1004
J 0
(-5475 2075);
DISPLAY 0.489362 (-5475 2075);
PAINT SKYBLUE (-5475 2075);
FORCEPROP 0 LAST $SEC 1
J 0
(-5300 2175);
DISPLAY 0.680851 (-5300 2175);
PAINT MONO (-5300 2175);
DISPLAY INVISIBLE (-5300 2175);
FORCEPROP 0 LAST CDS_SEC 1
J 0
(-5300 2175);
DISPLAY 1.021277 (-5300 2175);
DISPLAY INVISIBLE (-5300 2175);
FORCEPROP 1 LASTPIN (-5350 2075) $PN 1
J 0
(-5338 2087);
DISPLAY 0.489362 (-5338 2087);
PAINT MONO (-5338 2087);
FORCEPROP 1 LASTPIN (-5150 2075) $PN 2
J 0
(-5188 2087);
DISPLAY 0.489362 (-5188 2087);
PAINT MONO (-5188 2087);
FORCEPROP 1 LAST TOLERANCE 5%
J 0
(-5025 2075);
DISPLAY 0.489362 (-5025 2075);
PAINT SKYBLUE (-5025 2075);
FORCEPROP 1 LAST VALUE 33
J 2
(-5050 2075);
DISPLAY 0.489362 (-5050 2075);
PAINT SKYBLUE (-5050 2075);
FORCEPROP 2 LAST CDS_LIB pure_quanta
J 0
(-5250 2075);
DISPLAY INVISIBLE (-5250 2075);
FORCEPROP 1 LAST PATH I17
J 0
(-5300 2225);
DISPLAY 0.978723 (-5300 2225);
PAINT WHITE (-5300 2225);
DISPLAY INVISIBLE (-5300 2225);
FORCEPROP 1 LAST WATTAGE 1/16W
J 2
(-5075 2200);
DISPLAY 0.617021 (-5075 2200);
PAINT SKYBLUE (-5075 2200);
DISPLAY INVISIBLE (-5075 2200);
FORCEPROP 1 LAST MATERIAL CHIP
J 0
(-5350 2200);
DISPLAY 0.617021 (-5350 2200);
PAINT SKYBLUE (-5350 2200);
DISPLAY INVISIBLE (-5350 2200);
FORCEPROP 1 LAST PART_NUMBER CS03302JB29
J 0
(-5350 2150);
DISPLAY 0.617021 (-5350 2150);
PAINT SKYBLUE (-5350 2150);
DISPLAY INVISIBLE (-5350 2150);
FORCEPROP 1 LAST PACK_TYPE 0402LF
J 0
(-4950 2075);
DISPLAY 0.617021 (-4950 2075);
PAINT SKYBLUE (-4950 2075);
DISPLAY INVISIBLE (-4950 2075);
FORCEADD OFFPAGE..1
(-6600 3400);
FORCEPROP 2 LAST $XR0 128 
J 0
(-6852 3400);
DISPLAY 0.638298 (-6852 3400);
PAINT MONO (-6852 3400);
FORCEPROP 2 LAST CDS_LIB mstr_standard
J 0
(-6600 3400);
DISPLAY INVISIBLE (-6600 3400);
FORCEPROP 2 LAST BOM_COST SB
J 0
(-6275 3450);
DISPLAY 1.361702 (-6275 3450);
PAINT WHITE (-6275 3450);
DISPLAY INVISIBLE (-6275 3450);
FORCEPROP 1 LAST OFFPAGE TRUE
J 0
(-6275 3275);
DISPLAY 0.872340 (-6275 3275);
PAINT GREEN (-6275 3275);
DISPLAY INVISIBLE (-6275 3275);
FORCEPROP 1 LAST COMMENT_BODY TRUE
J 0
(-6475 3300);
DISPLAY 0.872340 (-6475 3300);
PAINT GREEN (-6475 3300);
DISPLAY INVISIBLE (-6475 3300);
FORCEPROP 2 LAST PATH I18
J 0
(-6550 3475);
DISPLAY 1.021277 (-6550 3475);
DISPLAY INVISIBLE (-6550 3475);
FORCEPROP 2 LAST ROOM SB_PU_PD
J 0
(-6275 3450);
DISPLAY 1.361702 (-6275 3450);
PAINT RED (-6275 3450);
DISPLAY INVISIBLE (-6275 3450);
FORCEADD OFFPAGE..1
(-6575 2525);
FORCEPROP 2 LAST $XR0 114 
J 0
(-6857 2525);
DISPLAY 0.638298 (-6857 2525);
PAINT MONO (-6857 2525);
FORCEPROP 2 LAST CDS_LIB mstr_standard
J 0
(-6575 2525);
DISPLAY INVISIBLE (-6575 2525);
FORCEPROP 2 LAST BOM_COST SB
J 0
(-6250 2575);
DISPLAY 1.361702 (-6250 2575);
PAINT WHITE (-6250 2575);
DISPLAY INVISIBLE (-6250 2575);
FORCEPROP 1 LAST OFFPAGE TRUE
J 0
(-6250 2400);
DISPLAY 0.872340 (-6250 2400);
PAINT GREEN (-6250 2400);
DISPLAY INVISIBLE (-6250 2400);
FORCEPROP 1 LAST COMMENT_BODY TRUE
J 0
(-6450 2425);
DISPLAY 0.872340 (-6450 2425);
PAINT GREEN (-6450 2425);
DISPLAY INVISIBLE (-6450 2425);
FORCEPROP 2 LAST PATH I21
J 0
(-6525 2600);
DISPLAY 1.021277 (-6525 2600);
DISPLAY INVISIBLE (-6525 2600);
FORCEPROP 2 LAST ROOM SB_PU_PD
J 0
(-6250 2575);
DISPLAY 1.361702 (-6250 2575);
PAINT RED (-6250 2575);
DISPLAY INVISIBLE (-6250 2575);
FORCEADD OFFPAGE..1
(-6575 2075);
FORCEPROP 2 LAST $XR0 115 
J 0
(-6857 2075);
DISPLAY 0.638298 (-6857 2075);
PAINT MONO (-6857 2075);
FORCEPROP 2 LAST CDS_LIB mstr_standard
J 0
(-6575 2075);
DISPLAY INVISIBLE (-6575 2075);
FORCEPROP 2 LAST BOM_COST SB
J 0
(-6250 2125);
DISPLAY 1.361702 (-6250 2125);
PAINT WHITE (-6250 2125);
DISPLAY INVISIBLE (-6250 2125);
FORCEPROP 1 LAST OFFPAGE TRUE
J 0
(-6250 1950);
DISPLAY 0.872340 (-6250 1950);
PAINT GREEN (-6250 1950);
DISPLAY INVISIBLE (-6250 1950);
FORCEPROP 1 LAST COMMENT_BODY TRUE
J 0
(-6450 1975);
DISPLAY 0.872340 (-6450 1975);
PAINT GREEN (-6450 1975);
DISPLAY INVISIBLE (-6450 1975);
FORCEPROP 2 LAST PATH I23
J 0
(-6525 2150);
DISPLAY 1.021277 (-6525 2150);
DISPLAY INVISIBLE (-6525 2150);
FORCEPROP 2 LAST ROOM SB_PU_PD
J 0
(-6250 2125);
DISPLAY 1.361702 (-6250 2125);
PAINT RED (-6250 2125);
DISPLAY INVISIBLE (-6250 2125);
FORCEADD Q_RES..1
(-5250 1575);
FORCEPROP 1 LAST LOCATION R580
J 0
(-5450 1575);
DISPLAY 0.489362 (-5450 1575);
PAINT SKYBLUE (-5450 1575);
FORCEPROP 2 LAST $SEC 1
J 0
(-5300 1775);
DISPLAY 0.680851 (-5300 1775);
PAINT MONO (-5300 1775);
DISPLAY INVISIBLE (-5300 1775);
FORCEPROP 2 LAST CDS_SEC 1
J 0
(-5300 1775);
DISPLAY 0.680851 (-5300 1775);
DISPLAY INVISIBLE (-5300 1775);
FORCEPROP 1 LASTPIN (-5350 1575) $PN 1
J 0
(-5338 1587);
DISPLAY 0.489362 (-5338 1587);
PAINT MONO (-5338 1587);
FORCEPROP 1 LASTPIN (-5150 1575) $PN 2
J 0
(-5188 1587);
DISPLAY 0.489362 (-5188 1587);
PAINT MONO (-5188 1587);
FORCEPROP 1 LAST TOLERANCE 5%
J 0
(-5025 1575);
DISPLAY 0.489362 (-5025 1575);
PAINT SKYBLUE (-5025 1575);
FORCEPROP 1 LAST VALUE 33
J 2
(-5050 1575);
DISPLAY 0.489362 (-5050 1575);
PAINT SKYBLUE (-5050 1575);
FORCEPROP 2 LAST CDS_LIB pure_quanta
J 0
(-5250 1575);
DISPLAY INVISIBLE (-5250 1575);
FORCEPROP 1 LAST PATH I33
J 0
(-5300 1725);
DISPLAY 0.978723 (-5300 1725);
PAINT WHITE (-5300 1725);
DISPLAY INVISIBLE (-5300 1725);
FORCEPROP 1 LAST WATTAGE 1/16W
J 2
(-5075 1700);
DISPLAY 0.617021 (-5075 1700);
PAINT SKYBLUE (-5075 1700);
DISPLAY INVISIBLE (-5075 1700);
FORCEPROP 1 LAST MATERIAL CHIP
J 0
(-5350 1700);
DISPLAY 0.617021 (-5350 1700);
PAINT SKYBLUE (-5350 1700);
DISPLAY INVISIBLE (-5350 1700);
FORCEPROP 1 LAST PART_NUMBER CS03302JB29
J 0
(-5350 1650);
DISPLAY 0.617021 (-5350 1650);
PAINT SKYBLUE (-5350 1650);
DISPLAY INVISIBLE (-5350 1650);
FORCEPROP 1 LAST PACK_TYPE 0402LF
J 0
(-4950 1575);
DISPLAY 0.617021 (-4950 1575);
PAINT SKYBLUE (-4950 1575);
DISPLAY INVISIBLE (-4950 1575);
FORCEADD OFFPAGE..1
(-6575 1575);
FORCEPROP 2 LAST $XR0 116 
J 0
(-6857 1575);
DISPLAY 0.638298 (-6857 1575);
PAINT MONO (-6857 1575);
FORCEPROP 2 LAST BOM_COST SB
J 0
(-6250 1625);
DISPLAY 1.361702 (-6250 1625);
PAINT WHITE (-6250 1625);
DISPLAY INVISIBLE (-6250 1625);
FORCEPROP 2 LAST CDS_LIB mstr_standard
J 0
(-6575 1575);
DISPLAY INVISIBLE (-6575 1575);
FORCEPROP 1 LAST OFFPAGE TRUE
J 0
(-6250 1450);
DISPLAY 0.872340 (-6250 1450);
PAINT GREEN (-6250 1450);
DISPLAY INVISIBLE (-6250 1450);
FORCEPROP 1 LAST COMMENT_BODY TRUE
J 0
(-6450 1475);
DISPLAY 0.872340 (-6450 1475);
PAINT GREEN (-6450 1475);
DISPLAY INVISIBLE (-6450 1475);
FORCEPROP 2 LAST PATH I34
J 0
(-6525 1650);
DISPLAY 0.680851 (-6525 1650);
DISPLAY INVISIBLE (-6525 1650);
FORCEPROP 2 LAST ROOM SB_PU_PD
J 0
(-6250 1625);
DISPLAY 1.361702 (-6250 1625);
PAINT RED (-6250 1625);
DISPLAY INVISIBLE (-6250 1625);
FORCEADD UNIVERSAL_GND..1
R 7
(-2250 5100);
FORCEPROP 3 LASTPIN (-2200 5100) SIG_NAME GND\g
J 0
(-2190 5110);
DISPLAY 0.659574 (-2190 5110);
PAINT MONO (-2190 5110);
DISPLAY INVISIBLE (-2190 5110);
FORCEPROP 2 LAST CDS_LIB pure_quanta_power
R 1
J 0
(-2250 5100);
DISPLAY INVISIBLE (-2250 5100);
FORCEPROP 1 LAST PATH I35
R 1
J 0
(-2250 5175);
DISPLAY 0.872340 (-2250 5175);
PAINT AQUA (-2250 5175);
DISPLAY INVISIBLE (-2250 5175);
FORCEPROP 1 LAST HDL_POWER GND
R 1
J 1
(-2325 5125);
DISPLAY 0.872340 (-2325 5125);
PAINT GREEN (-2325 5125);
DISPLAY INVISIBLE (-2325 5125);
FORCEADD MOSFET_DUAL_6P..1
(-1775 5050);
FORCEPROP 1 LAST LOCATION Q4
J 0
(-1922 5259);
DISPLAY 0.489362 (-1922 5259);
PAINT SKYBLUE (-1922 5259);
FORCEPROP 2 LAST $SEC 1
J 0
(-1900 5400);
DISPLAY 0.680851 (-1900 5400);
PAINT MONO (-1900 5400);
DISPLAY INVISIBLE (-1900 5400);
FORCEPROP 2 LAST CDS_SEC 1
J 0
(-1900 5400);
DISPLAY 0.680851 (-1900 5400);
DISPLAY INVISIBLE (-1900 5400);
FORCEPROP 2 LASTPIN (-2075 5000) $PN 6
J 2
(-2085 5010);
DISPLAY 0.489362 (-2085 5010);
PAINT MONO (-2085 5010);
FORCEPROP 2 LASTPIN (-1475 5000) $PN 3
J 0
(-1465 5010);
DISPLAY 0.489362 (-1465 5010);
PAINT MONO (-1465 5010);
FORCEPROP 2 LASTPIN (-2075 5050) $PN 2
J 2
(-2085 5060);
DISPLAY 0.489362 (-2085 5060);
PAINT MONO (-2085 5060);
FORCEPROP 2 LASTPIN (-1475 5050) $PN 5
J 0
(-1465 5060);
DISPLAY 0.489362 (-1465 5060);
PAINT MONO (-1465 5060);
FORCEPROP 2 LASTPIN (-2075 5100) $PN 1
J 2
(-2085 5110);
DISPLAY 0.489362 (-2085 5110);
PAINT MONO (-2085 5110);
FORCEPROP 2 LASTPIN (-1475 5100) $PN 4
J 0
(-1465 5110);
DISPLAY 0.489362 (-1465 5110);
PAINT MONO (-1465 5110);
FORCEPROP 2 LAST PART_TYPE SMLF
J 0
(-1900 5350);
DISPLAY 0.680851 (-1900 5350);
FORCEPROP 1 LAST MATERIAL IC
J 0
(-1922 5173);
DISPLAY 0.489362 (-1922 5173);
PAINT SKYBLUE (-1922 5173);
FORCEPROP 2 LAST VALUE 2N7002KDW
J 0
(-1900 5300);
DISPLAY 0.489362 (-1900 5300);
PAINT SKYBLUE (-1900 5300);
FORCEPROP 1 LAST PART_NUMBER BAM70020047
J 0
(-1922 5217);
DISPLAY 0.489362 (-1922 5217);
PAINT SKYBLUE (-1922 5217);
FORCEPROP 1 LAST CDS_LMAN_SYM_OUTLINE -150,100,150,-100
J 0
(-1775 5050);
DISPLAY 0.468085 (-1775 5050);
PAINT GREEN (-1775 5050);
DISPLAY INVISIBLE (-1775 5050);
FORCEPROP 1 LAST NEEDS_NO_SIZE TRUE
J 0
(-1775 5049);
DISPLAY 0.468085 (-1775 5049);
PAINT GREEN (-1775 5049);
DISPLAY INVISIBLE (-1775 5049);
FORCEPROP 2 LAST CDS_LIB pure_quanta
J 0
(-1775 5050);
DISPLAY INVISIBLE (-1775 5050);
FORCEPROP 1 LAST PATH I38
J 0
(-1775 5050);
DISPLAY 0.723404 (-1775 5050);
PAINT GREEN (-1775 5050);
DISPLAY INVISIBLE (-1775 5050);
FORCEADD OFFPAGE..5
(-2850 5000);
FORCEPROP 2 LAST $XR0 132 
J 0
(-3105 5000);
DISPLAY 0.638298 (-3105 5000);
PAINT MONO (-3105 5000);
FORCEPROP 2 LAST CDS_LIB standard
J 0
(-2850 5000);
DISPLAY INVISIBLE (-2850 5000);
FORCEPROP 1 LAST OFFPAGE TRUE
J 0
(-2525 4875);
DISPLAY 0.872340 (-2525 4875);
PAINT GREEN (-2525 4875);
DISPLAY INVISIBLE (-2525 4875);
FORCEPROP 1 LAST COMMENT_BODY TRUE
J 0
(-2750 4925);
DISPLAY 0.872340 (-2750 4925);
PAINT GREEN (-2750 4925);
DISPLAY INVISIBLE (-2750 4925);
FORCEPROP 2 LAST PATH I39
J 0
(-2800 5075);
DISPLAY 0.680851 (-2800 5075);
DISPLAY INVISIBLE (-2800 5075);
FORCEADD OFFPAGE..4
(-950 5050);
FORCEPROP 2 LAST $XR0 132 
J 0
(-764 5050);
DISPLAY 0.638298 (-764 5050);
PAINT MONO (-764 5050);
FORCEPROP 2 LAST CDS_LIB standard
J 0
(-950 5050);
DISPLAY INVISIBLE (-950 5050);
FORCEPROP 1 LAST OFFPAGE TRUE
J 0
(-625 4925);
DISPLAY 0.872340 (-625 4925);
PAINT GREEN (-625 4925);
DISPLAY INVISIBLE (-625 4925);
FORCEPROP 1 LAST COMMENT_BODY TRUE
J 0
(-975 4950);
DISPLAY 0.872340 (-975 4950);
PAINT GREEN (-975 4950);
DISPLAY INVISIBLE (-975 4950);
FORCEPROP 2 LAST PATH I40
J 0
(-775 5125);
DISPLAY 0.680851 (-775 5125);
DISPLAY INVISIBLE (-775 5125);
FORCEADD UNIVERSAL_GND..1
R 1
(-1375 5100);
FORCEPROP 3 LASTPIN (-1425 5100) SIG_NAME GND\g
J 0
(-1415 5110);
DISPLAY 0.659574 (-1415 5110);
PAINT MONO (-1415 5110);
DISPLAY INVISIBLE (-1415 5110);
FORCEPROP 2 LAST CDS_LIB pure_quanta_power
J 2
(-1375 5100);
DISPLAY INVISIBLE (-1375 5100);
FORCEPROP 1 LAST PATH I42
R 1
J 0
(-1375 5175);
DISPLAY 0.872340 (-1375 5175);
PAINT AQUA (-1375 5175);
DISPLAY INVISIBLE (-1375 5175);
FORCEPROP 1 LAST HDL_POWER GND
R 1
J 1
(-1300 5125);
DISPLAY 0.872340 (-1300 5125);
PAINT GREEN (-1300 5125);
DISPLAY INVISIBLE (-1300 5125);
FORCEADD UNIVERSAL_POWER..1
(-3550 5525);
FORCEPROP 3 LASTPIN (-3550 5475) SIG_NAME P3V3_STBY\g
J 0
(-3540 5485);
DISPLAY 0.659574 (-3540 5485);
PAINT MONO (-3540 5485);
DISPLAY INVISIBLE (-3540 5485);
FORCEPROP 1 LAST HDL_POWER P3V3_STBY
J 1
(-3550 5575);
DISPLAY 0.489362 (-3550 5575);
PAINT GREEN (-3550 5575);
FORCEPROP 2 LAST CDS_LIB pure_quanta_power
J 0
(-3550 5525);
DISPLAY INVISIBLE (-3550 5525);
FORCEPROP 1 LAST PATH I43
J 0
(-3500 5550);
DISPLAY 0.872340 (-3500 5550);
PAINT AQUA (-3500 5550);
DISPLAY INVISIBLE (-3500 5550);
FORCEADD Q_RES..2
R 2
(-3550 5275);
FORCEPROP 1 LAST LOCATION R994
J 2
(-3600 5475);
DISPLAY 0.489362 (-3600 5475);
PAINT SKYBLUE (-3600 5475);
FORCEPROP 0 LAST $SEC 1
J 0
(-3600 5525);
DISPLAY 0.680851 (-3600 5525);
PAINT MONO (-3600 5525);
DISPLAY INVISIBLE (-3600 5525);
FORCEPROP 0 LAST CDS_SEC 1
J 0
(-3600 5525);
DISPLAY 0.680851 (-3600 5525);
DISPLAY INVISIBLE (-3600 5525);
FORCEPROP 1 LASTPIN (-3550 5375) $PN 1
J 2
(-3555 5337);
DISPLAY 0.489362 (-3555 5337);
PAINT MONO (-3555 5337);
FORCEPROP 1 LASTPIN (-3550 5175) $PN 2
J 2
(-3555 5185);
DISPLAY 0.489362 (-3555 5185);
PAINT MONO (-3555 5185);
FORCEPROP 1 LAST WATTAGE 1/16W
J 2
(-3600 5325);
DISPLAY 0.489362 (-3600 5325);
PAINT SKYBLUE (-3600 5325);
FORCEPROP 1 LAST MATERIAL CHIP
J 2
(-3600 5275);
DISPLAY 0.489362 (-3600 5275);
PAINT SKYBLUE (-3600 5275);
FORCEPROP 1 LAST TOLERANCE 1%
J 2
(-3605 5375);
DISPLAY 0.489362 (-3605 5375);
PAINT SKYBLUE (-3605 5375);
FORCEPROP 1 LAST VALUE 10K
J 2
(-3605 5425);
DISPLAY 0.489362 (-3605 5425);
PAINT SKYBLUE (-3605 5425);
FORCEPROP 1 LAST PART_NUMBER TMP_QCS31002FB26
J 2
(-3600 5225);
DISPLAY 0.489362 (-3600 5225);
PAINT SKYBLUE (-3600 5225);
FORCEPROP 1 LAST PACK_TYPE 0402LF
J 2
(-3600 5175);
DISPLAY 0.489362 (-3600 5175);
PAINT SKYBLUE (-3600 5175);
FORCEPROP 2 LAST CDS_LIB pure_quanta
J 0
(-3550 5275);
DISPLAY INVISIBLE (-3550 5275);
FORCEPROP 1 LAST PATH I44
J 2
(-3600 5450);
DISPLAY 0.978723 (-3600 5450);
PAINT WHITE (-3600 5450);
DISPLAY INVISIBLE (-3600 5450);
FORCEADD UNIVERSAL_POWER..1
(-475 5450);
FORCEPROP 3 LASTPIN (-475 5400) SIG_NAME PVDD18_S5_P0\g
J 0
(-465 5410);
DISPLAY 0.659574 (-465 5410);
PAINT MONO (-465 5410);
DISPLAY INVISIBLE (-465 5410);
FORCEPROP 1 LAST HDL_POWER PVDD18_S5_P0
J 1
(-475 5500);
DISPLAY 0.489362 (-475 5500);
PAINT GREEN (-475 5500);
FORCEPROP 2 LAST CDS_LIB pure_quanta_power
J 0
(-475 5450);
DISPLAY INVISIBLE (-475 5450);
FORCEPROP 1 LAST PATH I45
J 0
(-425 5475);
DISPLAY 0.872340 (-425 5475);
PAINT AQUA (-425 5475);
DISPLAY INVISIBLE (-425 5475);
FORCEADD Q_RES..2
(-475 5250);
FORCEPROP 1 LAST LOCATION R437
J 0
(-425 5300);
DISPLAY 0.489362 (-425 5300);
PAINT SKYBLUE (-425 5300);
FORCEPROP 0 LAST $SEC 1
J 0
(-425 5325);
DISPLAY 0.680851 (-425 5325);
PAINT MONO (-425 5325);
DISPLAY INVISIBLE (-425 5325);
FORCEPROP 0 LAST CDS_SEC 1
J 0
(-425 5325);
DISPLAY 0.680851 (-425 5325);
DISPLAY INVISIBLE (-425 5325);
FORCEPROP 1 LASTPIN (-475 5350) $PN 1
J 0
(-470 5312);
DISPLAY 0.489362 (-470 5312);
PAINT MONO (-470 5312);
FORCEPROP 1 LASTPIN (-475 5150) $PN 2
J 0
(-470 5160);
DISPLAY 0.489362 (-470 5160);
PAINT MONO (-470 5160);
FORCEPROP 1 LAST VALUE 2.2K
J 0
(-425 5250);
DISPLAY 0.489362 (-425 5250);
PAINT SKYBLUE (-425 5250);
FORCEPROP 1 LAST PART_NUMBER CS22202JB07
J 0
(-425 5200);
DISPLAY 0.489362 (-425 5200);
PAINT SKYBLUE (-425 5200);
FORCEPROP 1 LAST PACK_TYPE 0402LF
J 0
(-425 5150);
DISPLAY 0.489362 (-425 5150);
PAINT SKYBLUE (-425 5150);
FORCEPROP 2 LAST CDS_LIB pure_quanta
J 0
(-475 5250);
DISPLAY INVISIBLE (-475 5250);
FORCEPROP 1 LAST PATH I46
J 0
(-425 5425);
DISPLAY 0.978723 (-425 5425);
PAINT WHITE (-425 5425);
DISPLAY INVISIBLE (-425 5425);
FORCEPROP 1 LAST WATTAGE 1/16W
J 0
(-435 5225);
DISPLAY 0.510638 (-435 5225);
PAINT SKYBLUE (-435 5225);
DISPLAY INVISIBLE (-435 5225);
FORCEPROP 1 LAST MATERIAL CHIP
J 0
(-435 5175);
DISPLAY 0.510638 (-435 5175);
PAINT SKYBLUE (-435 5175);
DISPLAY INVISIBLE (-435 5175);
FORCEPROP 1 LAST TOLERANCE 5%
J 0
(-430 5275);
DISPLAY 0.510638 (-430 5275);
PAINT SKYBLUE (-430 5275);
DISPLAY INVISIBLE (-430 5275);
FORCEADD Q_RES..1
R 2
(-2375 4725);
FORCEPROP 1 LAST LOCATION R1009
J 2
(-2425 4725);
DISPLAY 0.489362 (-2425 4725);
PAINT SKYBLUE (-2425 4725);
FORCEPROP 0 LAST $SEC 1
J 0
(-2125 4775);
DISPLAY 0.680851 (-2125 4775);
PAINT MONO (-2125 4775);
DISPLAY INVISIBLE (-2125 4775);
FORCEPROP 2 LAST CDS_SEC 1
J 0
(-2425 4950);
DISPLAY 1.021277 (-2425 4950);
DISPLAY INVISIBLE (-2425 4950);
FORCEPROP 1 LASTPIN (-2275 4725) $PN 1
J 2
(-2287 4737);
DISPLAY 0.489362 (-2287 4737);
PAINT MONO (-2287 4737);
FORCEPROP 1 LASTPIN (-2475 4725) $PN 2
J 2
(-2437 4737);
DISPLAY 0.489362 (-2437 4737);
PAINT MONO (-2437 4737);
FORCEPROP 1 LAST MATERIAL CHIP
J 2
(-2425 4700);
DISPLAY 0.489362 (-2425 4700);
PAINT SKYBLUE (-2425 4700);
FORCEPROP 1 LAST VALUE 10K
J 0
(-2300 4700);
DISPLAY 0.489362 (-2300 4700);
PAINT SKYBLUE (-2300 4700);
FORCEPROP 1 LAST PACK_TYPE 0402LF
J 2
(-2125 4725);
DISPLAY 0.489362 (-2125 4725);
PAINT SKYBLUE (-2125 4725);
FORCEPROP 2 LAST CDS_LIB pure_quanta
J 2
(-2375 4725);
PAINT MONO (-2375 4725);
DISPLAY INVISIBLE (-2375 4725);
FORCEPROP 1 LAST PATH I48
J 2
(-2325 4875);
DISPLAY 0.978723 (-2325 4875);
PAINT WHITE (-2325 4875);
DISPLAY INVISIBLE (-2325 4875);
FORCEPROP 1 LAST WATTAGE 1/16W
J 0
(-2350 4575);
DISPLAY 0.638298 (-2350 4575);
PAINT SKYBLUE (-2350 4575);
DISPLAY INVISIBLE (-2350 4575);
FORCEPROP 1 LAST TOLERANCE 1%
J 2
(-2375 4625);
DISPLAY 0.638298 (-2375 4625);
PAINT SKYBLUE (-2375 4625);
DISPLAY INVISIBLE (-2375 4625);
FORCEPROP 1 LAST PART_NUMBER TMP_QCS31002FB26
J 2
(-2325 4825);
DISPLAY 0.638298 (-2325 4825);
PAINT SKYBLUE (-2325 4825);
DISPLAY INVISIBLE (-2325 4825);
FORCEADD UNIVERSAL_POWER..1
(-2025 4875);
FORCEPROP 3 LASTPIN (-2025 4825) SIG_NAME P3V3_STBY\g
J 0
(-2015 4835);
DISPLAY 0.659574 (-2015 4835);
PAINT MONO (-2015 4835);
DISPLAY INVISIBLE (-2015 4835);
FORCEPROP 1 LAST HDL_POWER P3V3_STBY
J 1
(-2025 4925);
DISPLAY 0.489362 (-2025 4925);
PAINT GREEN (-2025 4925);
FORCEPROP 2 LAST CDS_LIB pure_quanta_power
J 0
(-2025 4875);
PAINT MONO (-2025 4875);
DISPLAY INVISIBLE (-2025 4875);
FORCEPROP 1 LAST PATH I49
J 0
(-1975 4900);
DISPLAY 0.872340 (-1975 4900);
PAINT AQUA (-1975 4900);
DISPLAY INVISIBLE (-1975 4900);
FORCEADD Q_RES..1
(-825 5000);
FORCEPROP 1 LAST LOCATION R1311
J 0
(-975 5000);
DISPLAY 0.489362 (-975 5000);
PAINT SKYBLUE (-975 5000);
FORCEPROP 0 LAST $SEC 1
J 0
(-975 5025);
DISPLAY 0.680851 (-975 5025);
PAINT MONO (-975 5025);
DISPLAY INVISIBLE (-975 5025);
FORCEPROP 0 LAST CDS_SEC 1
J 0
(-975 5025);
DISPLAY 0.680851 (-975 5025);
DISPLAY INVISIBLE (-975 5025);
FORCEPROP 1 LASTPIN (-925 5000) $PN 1
J 0
(-913 5012);
DISPLAY 0.489362 (-913 5012);
PAINT MONO (-913 5012);
FORCEPROP 1 LASTPIN (-725 5000) $PN 2
J 0
(-763 5012);
DISPLAY 0.489362 (-763 5012);
PAINT MONO (-763 5012);
FORCEPROP 1 LAST TOLERANCE 5%
J 0
(-750 4975);
DISPLAY 0.489362 (-750 4975);
PAINT SKYBLUE (-750 4975);
FORCEPROP 1 LAST VALUE 33
J 2
(-925 4975);
DISPLAY 0.489362 (-925 4975);
PAINT SKYBLUE (-925 4975);
FORCEPROP 2 LAST CDS_LIB pure_quanta
J 0
(-825 5000);
DISPLAY INVISIBLE (-825 5000);
FORCEPROP 1 LAST PATH I50
J 0
(-875 5150);
DISPLAY 0.978723 (-875 5150);
PAINT WHITE (-875 5150);
DISPLAY INVISIBLE (-875 5150);
FORCEPROP 1 LAST WATTAGE 1/16W
J 2
(-650 5125);
DISPLAY 0.617021 (-650 5125);
PAINT SKYBLUE (-650 5125);
DISPLAY INVISIBLE (-650 5125);
FORCEPROP 1 LAST MATERIAL CHIP
J 0
(-925 5125);
DISPLAY 0.617021 (-925 5125);
PAINT SKYBLUE (-925 5125);
DISPLAY INVISIBLE (-925 5125);
FORCEPROP 1 LAST PART_NUMBER CS03302JB29
J 0
(-925 5075);
DISPLAY 0.617021 (-925 5075);
PAINT SKYBLUE (-925 5075);
DISPLAY INVISIBLE (-925 5075);
FORCEPROP 1 LAST PACK_TYPE 0402LF
J 0
(-525 5000);
DISPLAY 0.617021 (-525 5000);
PAINT SKYBLUE (-525 5000);
DISPLAY INVISIBLE (-525 5000);
FORCEADD OFFPAGE..2
(-400 5000);
FORCEPROP 2 LAST $XR1 55 
J 0
(-121 5000);
DISPLAY 0.638298 (-121 5000);
PAINT MONO (-121 5000);
FORCEPROP 2 LAST $XR0 28 
J 0
(-211 5000);
DISPLAY 0.638298 (-211 5000);
PAINT MONO (-211 5000);
FORCEPROP 2 LAST CDS_LIB standard
J 0
(-400 5000);
DISPLAY INVISIBLE (-400 5000);
FORCEPROP 1 LAST OFFPAGE TRUE
J 0
(-75 4875);
DISPLAY 0.872340 (-75 4875);
PAINT GREEN (-75 4875);
DISPLAY INVISIBLE (-75 4875);
FORCEPROP 1 LAST COMMENT_BODY TRUE
J 0
(-445 4905);
DISPLAY 0.872340 (-445 4905);
PAINT GREEN (-445 4905);
DISPLAY INVISIBLE (-445 4905);
FORCEPROP 2 LAST PATH I51
J 0
(-100 5050);
DISPLAY 0.680851 (-100 5050);
DISPLAY INVISIBLE (-100 5050);
FORCEADD Q_RES..1
(-5225 4050);
FORCEPROP 1 LAST LOCATION R116
J 0
(-5450 4050);
DISPLAY 0.489362 (-5450 4050);
PAINT SKYBLUE (-5450 4050);
FORCEPROP 0 LAST $SEC 1
J 0
(-5025 4200);
DISPLAY 0.680851 (-5025 4200);
PAINT MONO (-5025 4200);
DISPLAY INVISIBLE (-5025 4200);
FORCEPROP 0 LAST CDS_SEC 1
J 0
(-5025 4200);
DISPLAY 1.021277 (-5025 4200);
DISPLAY INVISIBLE (-5025 4200);
FORCEPROP 1 LASTPIN (-5325 4050) $PN 1
J 0
(-5313 4062);
DISPLAY 0.489362 (-5313 4062);
PAINT MONO (-5313 4062);
FORCEPROP 1 LASTPIN (-5125 4050) $PN 2
J 0
(-5163 4062);
DISPLAY 0.489362 (-5163 4062);
PAINT MONO (-5163 4062);
FORCEPROP 1 LAST WATTAGE 1/16W
J 2
(-5325 3950);
DISPLAY 0.489362 (-5325 3950);
PAINT SKYBLUE (-5325 3950);
FORCEPROP 1 LAST MATERIAL CHIP
J 0
(-5000 4050);
DISPLAY 0.489362 (-5000 4050);
PAINT SKYBLUE (-5000 4050);
FORCEPROP 1 LAST TOLERANCE 5%
J 0
(-5425 4000);
DISPLAY 0.489362 (-5425 4000);
PAINT SKYBLUE (-5425 4000);
FORCEPROP 1 LAST VALUE 33
J 2
(-5050 4050);
DISPLAY 0.489362 (-5050 4050);
PAINT SKYBLUE (-5050 4050);
FORCEPROP 1 LAST PART_NUMBER CS03302JB29
J 0
(-5100 4000);
DISPLAY 0.489362 (-5100 4000);
PAINT SKYBLUE (-5100 4000);
FORCEPROP 1 LAST PACK_TYPE 0402LF
J 0
(-5100 3950);
DISPLAY 0.489362 (-5100 3950);
PAINT SKYBLUE (-5100 3950);
FORCEPROP 2 LAST BOM_COST PCH
J 0
(-5075 4125);
DISPLAY 1.361702 (-5075 4125);
DISPLAY INVISIBLE (-5075 4125);
FORCEPROP 2 LAST CDS_LIB pure_quanta
J 0
(-5225 4050);
DISPLAY INVISIBLE (-5225 4050);
FORCEPROP 1 LAST PATH I8
J 0
(-5275 4200);
DISPLAY 0.978723 (-5275 4200);
PAINT WHITE (-5275 4200);
DISPLAY INVISIBLE (-5275 4200);
FORCEPROP 2 LAST ROOM PCH
J 0
(-5075 4125);
DISPLAY 1.361702 (-5075 4125);
PAINT RED (-5075 4125);
DISPLAY INVISIBLE (-5075 4125);
FORCEADD Q_RES..1
(-5225 3575);
FORCEPROP 1 LAST LOCATION R1005
J 0
(-5475 3575);
DISPLAY 0.489362 (-5475 3575);
PAINT SKYBLUE (-5475 3575);
FORCEPROP 0 LAST $SEC 1
J 0
(-5275 3675);
DISPLAY 0.680851 (-5275 3675);
PAINT MONO (-5275 3675);
DISPLAY INVISIBLE (-5275 3675);
FORCEPROP 0 LAST CDS_SEC 1
J 0
(-5275 3675);
DISPLAY 1.021277 (-5275 3675);
DISPLAY INVISIBLE (-5275 3675);
FORCEPROP 1 LASTPIN (-5325 3575) $PN 1
J 0
(-5313 3587);
DISPLAY 0.489362 (-5313 3587);
PAINT MONO (-5313 3587);
FORCEPROP 1 LASTPIN (-5125 3575) $PN 2
J 0
(-5163 3587);
DISPLAY 0.489362 (-5163 3587);
PAINT MONO (-5163 3587);
FORCEPROP 1 LAST TOLERANCE 5%
J 0
(-5000 3575);
DISPLAY 0.489362 (-5000 3575);
PAINT SKYBLUE (-5000 3575);
FORCEPROP 1 LAST VALUE 33
J 2
(-5025 3575);
DISPLAY 0.489362 (-5025 3575);
PAINT SKYBLUE (-5025 3575);
FORCEPROP 2 LAST CDS_LIB pure_quanta
J 0
(-5225 3575);
DISPLAY INVISIBLE (-5225 3575);
FORCEPROP 1 LAST PATH I9
J 0
(-5275 3725);
DISPLAY 0.978723 (-5275 3725);
PAINT WHITE (-5275 3725);
DISPLAY INVISIBLE (-5275 3725);
FORCEPROP 1 LAST WATTAGE 1/16W
J 2
(-5050 3700);
DISPLAY 0.617021 (-5050 3700);
PAINT SKYBLUE (-5050 3700);
DISPLAY INVISIBLE (-5050 3700);
FORCEPROP 1 LAST MATERIAL CHIP
J 0
(-5325 3700);
DISPLAY 0.617021 (-5325 3700);
PAINT SKYBLUE (-5325 3700);
DISPLAY INVISIBLE (-5325 3700);
FORCEPROP 1 LAST PART_NUMBER CS03302JB29
J 0
(-5325 3650);
DISPLAY 0.617021 (-5325 3650);
PAINT SKYBLUE (-5325 3650);
DISPLAY INVISIBLE (-5325 3650);
FORCEPROP 1 LAST PACK_TYPE 0402LF
J 0
(-4925 3575);
DISPLAY 0.617021 (-4925 3575);
PAINT SKYBLUE (-4925 3575);
DISPLAY INVISIBLE (-4925 3575);
FORCEADD QUANTA_TITLE_BLOCK_C..1
(0 0);
FORCEPROP 0 LAST CDS_CON_LAST_MODIFIED Fri Mar 11 14:53:12 2022
J 0
(-1885 15);
DISPLAY INVISIBLE (-1885 15);
FORCEPROP 1 LAST CUSTOM_TXT_CDS <CON_LAST_MODIFIED>
J 0
(-1885 15);
DISPLAY 0.978723 (-1885 15);
FORCEPROP 2 LAST CUSTOM_TXT_CDS <XR_PAGE_TITLE>
J 0
(-7890 5250);
DISPLAY 0.638298 (-7890 5250);
PAINT PINK (-7890 5250);
DISPLAY INVISIBLE (-7890 5250);
FORCEPROP 1 LAST CUSTOM_TXT_CDS <NAME_2>
J 0
(-3175 50);
FORCEPROP 1 LAST CUSTOM_TXT_CDS <NAME_1>
J 0
(-3175 175);
FORCEPROP 1 LAST CUSTOM_TXT_CDS <Q_NUMBER>
J 0
(-1403 103);
DISPLAY 1.212766 (-1403 103);
FORCEPROP 1 LAST CUSTOM_TXT_CDS <Q_PROJ>
J 0
(-2382 102);
DISPLAY 1.212766 (-2382 102);
FORCEPROP 1 LAST CUSTOM_TXT_CDS <Q_REV>
J 0
(-184 103);
DISPLAY 1.212766 (-184 103);
FORCEPROP 1 LAST CUSTOM_TXT_CDS <CON_PAGE_NUM> OF <CON_TOTAL_PAGES>
J 0
(-446 18);
DISPLAY 0.978723 (-446 18);
FORCEPROP 1 LAST Q_DEPT BU9
J 1
(-3763 49);
DISPLAY 1.957447 (-3763 49);
PAINT GREEN (-3763 49);
FORCEPROP 1 LAST Q_TITLE WAKE
J 0
(-9225 75);
DISPLAY 2.446809 (-9225 75);
PAINT GREEN (-9225 75);
FORCEPROP 2 LAST PAGE_BORDER TRUE
J 0
(-7890 5250);
DISPLAY 0.638298 (-7890 5250);
PAINT PINK (-7890 5250);
DISPLAY INVISIBLE (-7890 5250);
FORCEPROP 1 LAST CDS_LMAN_SYM_OUTLINE -9475,6775,100,-125
J 0
(0 0);
DISPLAY 0.468085 (0 0);
PAINT GREEN (0 0);
DISPLAY INVISIBLE (0 0);
FORCEPROP 2 LAST CDS_LIB pure_quanta
J 0
(0 0);
DISPLAY INVISIBLE (0 0);
FORCEPROP 1 LAST COMMENT_BODY TRUE
J 0
(12 -13);
DISPLAY 0.978723 (12 -13);
PAINT GREEN (12 -13);
DISPLAY INVISIBLE (12 -13);
FORCEPROP 2 LAST CDS_XR_PAGE_TITLE CR-132 : @T6G_MB_LIB.T6G(SCH_1):PAGE132
J 0
(-7890 5250);
DISPLAY 0.638298 (-7890 5250);
PAINT PINK (-7890 5250);
DISPLAY INVISIBLE (-7890 5250);
WIRE 16 -1 (-2075 5100)(-2200 5100);
WIRE 16 -1 (-1475 5100)(-1425 5100);
WIRE 16 -1 (-3550 5475)(-3550 5375);
WIRE 16 -1 (-475 5400)(-475 5350);
WIRE 16 -1 (-5325 4050)(-6550 4050);
FORCEPROP 2 LAST SIG_NAME OCP_SFF_WAKE_BUFF_N
J 0
(-6275 4060);
DISPLAY 0.489362 (-6275 4060);
WIRE 16 -1 (-6550 3575)(-5325 3575);
FORCEPROP 2 LAST SIG_NAME M2_1_PEWAKE_N
J 0
(-6275 3585);
DISPLAY 0.489362 (-6275 3585);
WIRE 16 -1 (-6550 3400)(-5325 3400);
FORCEPROP 2 LAST SIG_NAME M2_2_PEWAKE_N
J 0
(-6275 3410);
DISPLAY 0.489362 (-6275 3410);
WIRE 16 -1 (-5350 2525)(-6525 2525);
FORCEPROP 2 LAST SIG_NAME IRQ_SLOT1_WAKE_N
J 0
(-6360 2535);
DISPLAY 0.489362 (-6360 2535);
WIRE 16 -1 (-5350 2075)(-6525 2075);
FORCEPROP 2 LAST SIG_NAME IRQ_SLOT2_WAKE_N
J 0
(-6360 2085);
DISPLAY 0.489362 (-6360 2085);
WIRE 16 -1 (-5350 1575)(-6525 1575);
FORCEPROP 2 LAST SIG_NAME IRQ_SLOT3_WAKE_N
J 0
(-6360 1585);
DISPLAY 0.489362 (-6360 1585);
WIRE 16 -1 (-5150 1575)(-3550 1575);
WIRE 16 -1 (-3550 2075)(-3550 1575);
WIRE 16 -1 (-5150 2075)(-3550 2075);
WIRE 16 -1 (-3550 2525)(-3550 2075);
WIRE 16 -1 (-5150 2525)(-3550 2525);
WIRE 16 -1 (-3550 3400)(-3550 2525);
WIRE 16 -1 (-5125 3400)(-3550 3400);
WIRE 16 -1 (-3550 3575)(-3550 3400);
WIRE 16 -1 (-5125 3575)(-3550 3575);
WIRE 16 -1 (-3550 4050)(-3550 3575);
WIRE 16 -1 (-3550 5050)(-3550 4050);
WIRE 16 -1 (-3550 4050)(-5125 4050);
WIRE 16 -1 (-3550 5050)(-2075 5050);
FORCEPROP 0 LAST SIG_NAME IRQ_LVC3_WAKE_N
J 0
(-3435 5060);
DISPLAY 0.489362 (-3435 5060);
FORCEPROP 2 LASTPROP $XRERR UNIQUE?
J 0
(-3675 5060);
DISPLAY 0.638298 (-3675 5060);
PAINT MONO (-3675 5060);
DISPLAY INVISIBLE (-3675 5060);
WIRE 16 -1 (-3550 5050)(-3550 5175);
WIRE 16 -1 (-2725 4725)(-2475 4725);
WIRE 16 -1 (-2725 5000)(-2725 4725);
WIRE 16 -1 (-2725 5000)(-2075 5000);
FORCEPROP 0 LAST SIG_NAME IRQ_LVC3_WAKE
J 0
(-2560 5010);
DISPLAY 0.489362 (-2560 5010);
WIRE 16 -1 (-2800 5000)(-2725 5000);
WIRE 16 -1 (-2025 4825)(-2025 4725);
WIRE 16 -1 (-2025 4725)(-2275 4725);
WIRE 16 -1 (-925 5000)(-1475 5000);
FORCEPROP 0 LAST SIG_NAME IRQ_WAKE_R_N
J 0
(-1285 5010);
DISPLAY 0.489362 (-1285 5010);
FORCEPROP 2 LASTPROP $XRERR UNIQUE?
J 0
(-1525 5010);
DISPLAY 0.638298 (-1525 5010);
PAINT MONO (-1525 5010);
DISPLAY INVISIBLE (-1525 5010);
WIRE 16 -1 (-1475 5050)(-1000 5050);
FORCEPROP 0 LAST SIG_NAME IRQ_LVC3_WAKE
J 0
(-1285 5075);
DISPLAY 0.489362 (-1285 5075);
WIRE 16 -1 (-475 5150)(-475 5000);
WIRE 16 -1 (-475 5000)(-450 5000);
WIRE 16 -1 (-475 5000)(-725 5000);
FORCEPROP 0 LAST SIG_NAME IRQ_WAKE_N
J 0
(-710 5010);
DISPLAY 0.489362 (-710 5010);
DOT 1 (-475 5000);
DOT 1 (-2725 5000);
DOT 1 (-3550 2075);
DOT 1 (-3550 2525);
DOT 1 (-3550 3400);
DOT 1 (-3550 3575);
DOT 1 (-3550 4050);
DOT 1 (-3550 5050);
FORCENOTE
RISER
(-7825 1875) 0;
DISPLAY LEFT (-7825 1875);
DISPLAY 3.148936 (-7825 1875);
PAINT WHITE (-7825 1875);
FORCENOTE
OCP
(-7825 4000) 0;
DISPLAY LEFT (-7825 4000);
DISPLAY 3.148936 (-7825 4000);
PAINT WHITE (-7825 4000);
FORCENOTE
M.2
(-7825 3275) 0;
DISPLAY LEFT (-7825 3275);
DISPLAY 3.148936 (-7825 3275);
PAINT WHITE (-7825 3275);
QUIT
